# T6G (Grand Teton) — schematic netlist excerpt (pin names and nets, part order shuffled) for the footprints in the layout excerpt that follows; sources: Cadence DE-HDL packaged netlist, KiCad conversion of 04192023_DAF0TMB3IC0_F0TG_MB_C_brd_V02_OCP.brd

C9005  Q_CAP  0.1UF 25V 10% X7R  pkg 0402  page 85 : A = IRQ_HSC_FAULT_BUF_N ; B = GND
C668  Q_CAP  22UF 4V 20% X6S  pkg C0402  page 301 : A = P1V8_CPU0_RT2_1A ; B = GND
C1768  Q_CAP  10UF 16V 10% X6S  pkg C0805  page 257 : A = P3V3_MAX11617_VDD ; B = GND

(kicad_pcb
	(version 20260206)
	(generator "pcbnew")
	(generator_version "10.0")
	(general
		(thickness 1.6)
		(legacy_teardrops no)
	)
	(paper "A4")
	(title_block
		(title "04192023_DAF0TMB3IC0_F0TG_MB_C_brd_V02_OCP.brd")
		(comment 1 "Grand Teton / footprints 3532-3534 of 8354")
	)
	(layers
		(0 "F.Cu" signal "TOP")
		(4 "In1.Cu" signal "GND")
		(6 "In2.Cu" signal "IN1")
		(8 "In3.Cu" signal "GND1")
		(10 "In4.Cu" signal "IN2")
		(12 "In5.Cu" signal "GND2")
		(14 "In6.Cu" signal "IN3")
		(16 "In7.Cu" signal "GND3")
		(18 "In8.Cu" signal "VCC")
		(20 "In9.Cu" signal "VCC1")
		(22 "In10.Cu" signal "GND4")
		(24 "In11.Cu" signal "IN4")
		(26 "In12.Cu" signal "GND5")
		(28 "In13.Cu" signal "IN5")
		(30 "In14.Cu" signal "GND6")
		(32 "In15.Cu" signal "IN6")
		(34 "In16.Cu" signal "GND7")
		(2 "B.Cu" signal "BOTTOM")
		(9 "F.Adhes" user "F.Adhesive")
		(11 "B.Adhes" user "B.Adhesive")
		(13 "F.Paste" user "Package Geometry/Pastemask Top")
		(15 "B.Paste" user "Package Geometry/Pastemask Bottom")
		(5 "F.SilkS" user "Ref Des/Silkscreen Top")
		(7 "B.SilkS" user "Ref Des/Silkscreen Bottom")
		(1 "F.Mask" user "Board Geometry/Soldermask Top")
		(3 "B.Mask" user "Board Geometry/Soldermask Bottom")
		(17 "Dwgs.User" user "User.Drawings")
		(19 "Cmts.User" user "User.Comments")
		(21 "Eco1.User" user "User.Eco1")
		(23 "Eco2.User" user "User.Eco2")
		(25 "Edge.Cuts" user "Board Geometry/Outline")
		(27 "Margin" user)
		(31 "F.CrtYd" user "Package Geometry/Place Bound Top")
		(29 "B.CrtYd" user "Package Geometry/Place Bound Bottom")
		(35 "F.Fab" user "Ref Des/Assembly Top")
		(33 "B.Fab" user "Ref Des/Assembly Bottom")
	)
	(footprint ""
		(layer "F.Cu")
		(at 425.121324 -396.748 90)
		(property "Reference" "C668"
			(at 0 0 90)
			(layer "F.SilkS")
			(hide yes)
			(effects
				(font
					(size 1.27 1.27)
				)
			)
		)
		(property "Value" ""
			(at 0 0 90)
			(layer "F.Fab")
			(effects
				(font
					(size 1.27 1.27)
				)
			)
		)
		(duplicate_pad_numbers_are_jumpers no)
		(fp_line
			(start 0.7874 -0.4064)
			(end 0.7874 0.4064)
			(stroke
				(width 0.1524)
				(type default)
			)
			(layer "F.SilkS")
		)
		(fp_line
			(start -0.7874 -0.4064)
			(end 0.7874 -0.4064)
			(stroke
				(width 0.1524)
				(type default)
			)
			(layer "F.SilkS")
		)
		(fp_line
			(start 0.7874 0.4064)
			(end -0.7874 0.4064)
			(stroke
				(width 0.1524)
				(type default)
			)
			(layer "F.SilkS")
		)
		(fp_line
			(start -0.7874 0.4064)
			(end -0.7874 -0.4064)
			(stroke
				(width 0.1524)
				(type default)
			)
			(layer "F.SilkS")
		)
		(fp_line
			(start -0.12065 -0.305054)
			(end -0.12065 -0.2794)
			(stroke
				(width 0.1)
				(type default)
			)
			(layer "F.Fab")
		)
		(fp_line
			(start -0.67945 -0.305054)
			(end -0.12065 -0.305054)
			(stroke
				(width 0.1)
				(type default)
			)
			(layer "F.Fab")
		)
		(fp_line
			(start 0.67945 -0.3048)
			(end 0.67945 0.3048)
			(stroke
				(width 0.1)
				(type default)
			)
			(layer "F.Fab")
		)
		(fp_line
			(start 0.12065 -0.3048)
			(end 0.67945 -0.3048)
			(stroke
				(width 0.1)
				(type default)
			)
			(layer "F.Fab")
		)
		(fp_line
			(start 0.12065 -0.2794)
			(end 0.12065 -0.3048)
			(stroke
				(width 0.1)
				(type default)
			)
			(layer "F.Fab")
		)
		(fp_line
			(start -0.12065 -0.2794)
			(end 0.12065 -0.2794)
			(stroke
				(width 0.1)
				(type default)
			)
			(layer "F.Fab")
		)
		(fp_line
			(start 0.120396 0.2794)
			(end -0.12065 0.2794)
			(stroke
				(width 0.1)
				(type default)
			)
			(layer "F.Fab")
		)
		(fp_line
			(start -0.12065 0.2794)
			(end -0.12065 0.3048)
			(stroke
				(width 0.1)
				(type default)
			)
			(layer "F.Fab")
		)
		(fp_line
			(start 0.67945 0.3048)
			(end 0.120396 0.3048)
			(stroke
				(width 0.1)
				(type default)
			)
			(layer "F.Fab")
		)
		(fp_line
			(start 0.120396 0.3048)
			(end 0.120396 0.2794)
			(stroke
				(width 0.1)
				(type default)
			)
			(layer "F.Fab")
		)
		(fp_line
			(start -0.12065 0.3048)
			(end -0.67945 0.3048)
			(stroke
				(width 0.1)
				(type default)
			)
			(layer "F.Fab")
		)
		(fp_line
			(start -0.67945 0.3048)
			(end -0.67945 -0.305054)
			(stroke
				(width 0.1)
				(type default)
			)
			(layer "F.Fab")
		)
		(pad "1" smd circle
			(at -0.40005 0 90)
			(size 0 0)
			(layers "F.Cu" "F.Mask" "F.Paste")
			(net "P1V8_CPU0_RT2_1A")
		)
		(pad "2" smd circle
			(at 0.40005 0 90)
			(size 0 0)
			(layers "F.Cu" "F.Mask" "F.Paste")
			(net "GND")
		)
	)
	(footprint ""
		(layer "F.Cu")
		(at 162.052 -107.696 90)
		(property "Reference" "C9005"
			(at 0 0 90)
			(layer "F.SilkS")
			(hide yes)
			(effects
				(font
					(size 1.27 1.27)
				)
			)
		)
		(property "Value" ""
			(at 0 0 90)
			(layer "F.Fab")
			(effects
				(font
					(size 1.27 1.27)
				)
			)
		)
		(duplicate_pad_numbers_are_jumpers no)
		(fp_line
			(start 0.7874 -0.4064)
			(end 0.7874 0.4064)
			(stroke
				(width 0.1524)
				(type default)
			)
			(layer "F.SilkS")
		)
		(fp_line
			(start -0.7874 -0.4064)
			(end 0.7874 -0.4064)
			(stroke
				(width 0.1524)
				(type default)
			)
			(layer "F.SilkS")
		)
		(fp_line
			(start 0.7874 0.4064)
			(end -0.7874 0.4064)
			(stroke
				(width 0.1524)
				(type default)
			)
			(layer "F.SilkS")
		)
		(fp_line
			(start -0.7874 0.4064)
			(end -0.7874 -0.4064)
			(stroke
				(width 0.1524)
				(type default)
			)
			(layer "F.SilkS")
		)
		(fp_line
			(start -0.12065 -0.305054)
			(end -0.12065 -0.2794)
			(stroke
				(width 0.1)
				(type default)
			)
			(layer "F.Fab")
		)
		(fp_line
			(start -0.67945 -0.305054)
			(end -0.12065 -0.305054)
			(stroke
				(width 0.1)
				(type default)
			)
			(layer "F.Fab")
		)
		(fp_line
			(start 0.67945 -0.3048)
			(end 0.67945 0.3048)
			(stroke
				(width 0.1)
				(type default)
			)
			(layer "F.Fab")
		)
		(fp_line
			(start 0.12065 -0.3048)
			(end 0.67945 -0.3048)
			(stroke
				(width 0.1)
				(type default)
			)
			(layer "F.Fab")
		)
		(fp_line
			(start 0.12065 -0.2794)
			(end 0.12065 -0.3048)
			(stroke
				(width 0.1)
				(type default)
			)
			(layer "F.Fab")
		)
		(fp_line
			(start -0.12065 -0.2794)
			(end 0.12065 -0.2794)
			(stroke
				(width 0.1)
				(type default)
			)
			(layer "F.Fab")
		)
		(fp_line
			(start 0.120396 0.2794)
			(end -0.12065 0.2794)
			(stroke
				(width 0.1)
				(type default)
			)
			(layer "F.Fab")
		)
		(fp_line
			(start -0.12065 0.2794)
			(end -0.12065 0.3048)
			(stroke
				(width 0.1)
				(type default)
			)
			(layer "F.Fab")
		)
		(fp_line
			(start 0.67945 0.3048)
			(end 0.120396 0.3048)
			(stroke
				(width 0.1)
				(type default)
			)
			(layer "F.Fab")
		)
		(fp_line
			(start 0.120396 0.3048)
			(end 0.120396 0.2794)
			(stroke
				(width 0.1)
				(type default)
			)
			(layer "F.Fab")
		)
		(fp_line
			(start -0.12065 0.3048)
			(end -0.67945 0.3048)
			(stroke
				(width 0.1)
				(type default)
			)
			(layer "F.Fab")
		)
		(fp_line
			(start -0.67945 0.3048)
			(end -0.67945 -0.305054)
			(stroke
				(width 0.1)
				(type default)
			)
			(layer "F.Fab")
		)
		(pad "1" smd circle
			(at -0.40005 0 90)
			(size 0 0)
			(layers "F.Cu" "F.Mask" "F.Paste")
			(net "IRQ_HSC_FAULT_BUF_N")
		)
		(pad "2" smd circle
			(at 0.40005 0 90)
			(size 0 0)
			(layers "F.Cu" "F.Mask" "F.Paste")
			(net "GND")
		)
	)
	(footprint ""
		(layer "F.Cu")
		(at 329.838558 -38.409118)
		(property "Reference" "C1768"
			(at 0 0 0)
			(layer "F.SilkS")
			(hide yes)
			(effects
				(font
					(size 1.27 1.27)
				)
			)
		)
		(property "Value" ""
			(at 0 0 0)
			(layer "F.Fab")
			(effects
				(font
					(size 1.27 1.27)
				)
			)
		)
		(duplicate_pad_numbers_are_jumpers no)
		(fp_line
			(start -1.524 -0.762)
			(end 1.524 -0.762)
			(stroke
				(width 0.1524)
				(type default)
			)
			(layer "F.SilkS")
		)
		(fp_line
			(start -1.524 0.762)
			(end -1.524 -0.762)
			(stroke
				(width 0.1524)
				(type default)
			)
			(layer "F.SilkS")
		)
		(fp_line
			(start 1.524 -0.762)
			(end 1.524 0.762)
			(stroke
				(width 0.1524)
				(type default)
			)
			(layer "F.SilkS")
		)
		(fp_line
			(start 1.524 0.762)
			(end -1.524 0.762)
			(stroke
				(width 0.1524)
				(type default)
			)
			(layer "F.SilkS")
		)
		(fp_line
			(start -1.1049 -0.724916)
			(end -1.1049 0.724916)
			(stroke
				(width 0.1)
				(type default)
			)
			(layer "F.Fab")
		)
		(fp_line
			(start -1.1049 0.724916)
			(end 1.1049 0.724916)
			(stroke
				(width 0.1)
				(type default)
			)
			(layer "F.Fab")
		)
		(fp_line
			(start 1.1049 -0.724916)
			(end -1.1049 -0.724916)
			(stroke
				(width 0.1)
				(type default)
			)
			(layer "F.Fab")
		)
		(fp_line
			(start 1.1049 0.724916)
			(end 1.1049 -0.724916)
			(stroke
				(width 0.1)
				(type default)
			)
			(layer "F.Fab")
		)
		(pad "1" smd rect
			(at -0.889 0 180)
			(size 1.016 1.27)
			(layers "F.Cu" "F.Mask" "F.Paste")
			(net "P3V3_MAX11617_VDD")
		)
		(pad "2" smd rect
			(at 0.889 0 180)
			(size 1.016 1.27)
			(layers "F.Cu" "F.Mask" "F.Paste")
			(net "GND")
		)
	)
)
